# TIMECARD (Time Appliance Project (Time Card)) — schematic netlist excerpt (pin names and nets, part order shuffled) for the footprints in the layout excerpt that follows; sources: Cadence DE-HDL packaged netlist, KiCad conversion of R4006-B0001-02_R01.brd

R476  RESISTOR  100KOHM 1%  pkg SMC_0402R_H016  page 24 : \1\ = XP3R3V_FPGA ; \2\ = FPGA_EEPROM_I2C_SDA
R228  RESISTOR  1.13KOHM 1%  pkg SMC_0402R  page 31 : \1\ = UNNAMED_515_CAPACITOR_I130_1 ; \2\ = UNNAMED_515_CAPACITOR_I128_1

(kicad_pcb
	(version 20260206)
	(generator "pcbnew")
	(generator_version "10.0")
	(general
		(thickness 1.6)
		(legacy_teardrops no)
	)
	(paper "A4")
	(title_block
		(title "timecard-production-celestica-r4006 — R4006-B0001-02_R01.brd")
		(comment 1 "Time Appliance Project (Time Card) / footprints 20-21 of 1113")
	)
	(layers
		(0 "F.Cu" signal "TOP")
		(4 "In1.Cu" signal "L02_GND1")
		(6 "In2.Cu" signal "L03_SIG1")
		(8 "In3.Cu" signal "L04_GND2")
		(10 "In4.Cu" signal "L05_VCC1")
		(12 "In5.Cu" signal "L06_VCC2")
		(14 "In6.Cu" signal "L07_GND3")
		(16 "In7.Cu" signal "L08_SIG2")
		(18 "In8.Cu" signal "L09_GND4")
		(2 "B.Cu" signal "BOTTOM")
		(9 "F.Adhes" user "F.Adhesive")
		(11 "B.Adhes" user "B.Adhesive")
		(13 "F.Paste" user "Package Geometry/Pastemask Top")
		(15 "B.Paste" user "Package Geometry/Pastemask Bottom")
		(5 "F.SilkS" user "Ref Des/Silkscreen Top")
		(7 "B.SilkS" user "Ref Des/Silkscreen Bottom")
		(1 "F.Mask" user "Board Geometry/Soldermask Top")
		(3 "B.Mask" user "Board Geometry/Soldermask Bottom")
		(17 "Dwgs.User" user "User.Drawings")
		(19 "Cmts.User" user "User.Comments")
		(21 "Eco1.User" user "User.Eco1")
		(23 "Eco2.User" user "User.Eco2")
		(25 "Edge.Cuts" user "Board Geometry/Outline")
		(27 "Margin" user)
		(31 "F.CrtYd" user "Package Geometry/Place Bound Top")
		(29 "B.CrtYd" user "Package Geometry/Place Bound Bottom")
		(35 "F.Fab" user "Ref Des/Assembly Top")
		(33 "B.Fab" user "Ref Des/Assembly Bottom")
	)
	(footprint ""
		(layer "F.Cu")
		(at 133.858 -19.304 180)
		(property "Reference" "R476"
			(at 0.127 5.04063 0)
			(unlocked yes)
			(layer "F.SilkS")
			(effects
				(font
					(size 0.7874 0.5842)
					(thickness 0.1524)
				)
			)
		)
		(property "Value" "VAL*"
			(at 0.02032 2.13233 180)
			(unlocked yes)
			(layer "F.Fab")
			(hide yes)
			(effects
				(font
					(size 0.7874 0.5842)
					(thickness 0.1524)
				)
			)
		)
		(property "Tolerance" "TOL*"
			(at 0.044704 3.05435 180)
			(unlocked yes)
			(layer "Cmts.User")
			(hide yes)
			(effects
				(font
					(size 0.7874 0.5842)
					(thickness 0.1524)
				)
			)
		)
		(property "User Part Number" "PARTNUM*"
			(at 0.02032 4.024884 180)
			(unlocked yes)
			(layer "Cmts.User")
			(hide yes)
			(effects
				(font
					(size 0.7874 0.5842)
					(thickness 0.1524)
				)
			)
		)
		(property "Device Type" "RESISTOR-G155-11003-01,100KOHMA"
			(at 0.008382 1.210564 180)
			(unlocked yes)
			(layer "F.Fab")
			(hide yes)
			(effects
				(font
					(size 0.7874 0.5842)
					(thickness 0.1524)
				)
			)
		)
		(duplicate_pad_numbers_are_jumpers no)
		(fp_line
			(start 1.143 0.5588)
			(end 1.143 -0.5588)
			(stroke
				(width 0.1)
				(type default)
			)
			(layer "F.SilkS")
		)
		(fp_line
			(start 1.143 -0.5588)
			(end -1.143 -0.5588)
			(stroke
				(width 0.1)
				(type default)
			)
			(layer "F.SilkS")
		)
		(fp_line
			(start -1.143 0.5588)
			(end 1.143 0.5588)
			(stroke
				(width 0.1)
				(type default)
			)
			(layer "F.SilkS")
		)
		(fp_line
			(start -1.143 -0.5588)
			(end -1.143 0.5588)
			(stroke
				(width 0.1)
				(type default)
			)
			(layer "F.SilkS")
		)
		(fp_poly
			(pts
				(xy -1.143 0.5588) (xy 1.143 0.5588) (xy 1.143 -0.5588) (xy -1.143 -0.5588)
			)
			(stroke
				(width 0)
				(type default)
			)
			(fill no)
			(layer "F.CrtYd")
		)
		(fp_line
			(start 0.508 0.3048)
			(end 0.508 -0.3048)
			(stroke
				(width 0.1)
				(type default)
			)
			(layer "F.Fab")
		)
		(fp_line
			(start 0.508 -0.3048)
			(end -0.508 -0.3048)
			(stroke
				(width 0.1)
				(type default)
			)
			(layer "F.Fab")
		)
		(fp_line
			(start -0.508 0.3048)
			(end 0.508 0.3048)
			(stroke
				(width 0.1)
				(type default)
			)
			(layer "F.Fab")
		)
		(fp_line
			(start -0.508 -0.3048)
			(end -0.508 0.3048)
			(stroke
				(width 0.1)
				(type default)
			)
			(layer "F.Fab")
		)
		(pad "1" smd rect
			(at -0.5334 0 180)
			(size 0.7112 0.6096)
			(layers "F.Cu" "F.Mask" "F.Paste")
			(net "XP3R3V_FPGA")
		)
		(pad "2" smd rect
			(at 0.5334 0 180)
			(size 0.7112 0.6096)
			(layers "F.Cu" "F.Mask" "F.Paste")
			(net "FPGA_EEPROM_I2C_SDA")
		)
		(zone
			(layer "F.Cu")
			(hatch none 0.5)
			(connect_pads
				(clearance 0)
			)
			(min_thickness 0.25)
			(keepout
				(tracks allowed)
				(vias not_allowed)
				(pads allowed)
				(copperpour not_allowed)
				(footprints allowed)
			)
			(placement
				(enabled no)
				(sheetname "")
			)
			(fill
				(thermal_gap 0.5)
				(thermal_bridge_width 0.5)
				(island_removal_mode 0)
			)
			(polygon
				(pts
					(xy 133.9342 -19.6088) (xy 133.7818 -19.6088) (xy 133.7818 -18.9992) (xy 133.9342 -18.9992)
				)
			)
		)
		(zone
			(layer "F.Cu")
			(hatch none 0.5)
			(connect_pads
				(clearance 0)
			)
			(min_thickness 0.25)
			(keepout
				(tracks not_allowed)
				(vias allowed)
				(pads allowed)
				(copperpour not_allowed)
				(footprints allowed)
			)
			(placement
				(enabled no)
				(sheetname "")
			)
			(fill
				(thermal_gap 0.5)
				(thermal_bridge_width 0.5)
				(island_removal_mode 0)
			)
			(polygon
				(pts
					(xy 133.9342 -19.6088) (xy 133.7818 -19.6088) (xy 133.7818 -18.9992) (xy 133.9342 -18.9992)
				)
			)
		)
	)
	(footprint ""
		(layer "F.Cu")
		(at 146.685 -19.685 -90)
		(property "Reference" "R228"
			(at 3.21437 -2.667 0)
			(unlocked yes)
			(layer "F.SilkS")
			(effects
				(font
					(size 0.7874 0.5842)
					(thickness 0.1524)
				)
			)
		)
		(property "Value" "VAL*"
			(at 0.0508 2.245106 270)
			(unlocked yes)
			(layer "F.Fab")
			(hide yes)
			(effects
				(font
					(size 0.7874 0.5842)
					(thickness 0.1524)
				)
			)
		)
		(property "User Part Number" "PARTNUM*"
			(at 0.0762 4.302506 270)
			(unlocked yes)
			(layer "Cmts.User")
			(hide yes)
			(effects
				(font
					(size 0.7874 0.5842)
					(thickness 0.1524)
				)
			)
		)
		(property "Device Type" "RESISTOR-G152-00055-01,1.13KOHA"
			(at 0.0762 1.254506 270)
			(unlocked yes)
			(layer "F.Fab")
			(hide yes)
			(effects
				(font
					(size 0.7874 0.5842)
					(thickness 0.1524)
				)
			)
		)
		(property "Tolerance" "TOL*"
			(at 0.0508 3.261106 270)
			(unlocked yes)
			(layer "Cmts.User")
			(hide yes)
			(effects
				(font
					(size 0.7874 0.5842)
					(thickness 0.1524)
				)
			)
		)
		(duplicate_pad_numbers_are_jumpers no)
		(fp_line
			(start -1.143 0.5588)
			(end 1.143 0.5588)
			(stroke
				(width 0.1)
				(type default)
			)
			(layer "F.SilkS")
		)
		(fp_line
			(start 1.143 0.5588)
			(end 1.143 -0.5588)
			(stroke
				(width 0.1)
				(type default)
			)
			(layer "F.SilkS")
		)
		(fp_line
			(start -1.143 -0.5588)
			(end -1.143 0.5588)
			(stroke
				(width 0.1)
				(type default)
			)
			(layer "F.SilkS")
		)
		(fp_line
			(start 1.143 -0.5588)
			(end -1.143 -0.5588)
			(stroke
				(width 0.1)
				(type default)
			)
			(layer "F.SilkS")
		)
		(fp_rect
			(start -1.143 0.5588)
			(end 1.143 -0.5588)
			(stroke
				(width 0)
				(type default)
			)
			(fill no)
			(layer "F.CrtYd")
		)
		(fp_line
			(start -0.508 0.3048)
			(end 0.508 0.3048)
			(stroke
				(width 0.1)
				(type default)
			)
			(layer "F.Fab")
		)
		(fp_line
			(start 0.508 0.3048)
			(end 0.508 -0.3048)
			(stroke
				(width 0.1)
				(type default)
			)
			(layer "F.Fab")
		)
		(fp_line
			(start -0.508 -0.3048)
			(end -0.508 0.3048)
			(stroke
				(width 0.1)
				(type default)
			)
			(layer "F.Fab")
		)
		(fp_line
			(start 0.508 -0.3048)
			(end -0.508 -0.3048)
			(stroke
				(width 0.1)
				(type default)
			)
			(layer "F.Fab")
		)
		(pad "1" smd rect
			(at -0.5334 0 270)
			(size 0.7112 0.6096)
			(layers "F.Cu" "F.Mask" "F.Paste")
			(net "UNNAMED_515_CAPACITOR_I130_1")
		)
		(pad "2" smd rect
			(at 0.5334 0 270)
			(size 0.7112 0.6096)
			(layers "F.Cu" "F.Mask" "F.Paste")
			(net "UNNAMED_515_CAPACITOR_I128_1")
		)
		(zone
			(layer "F.Cu")
			(hatch none 0.5)
			(connect_pads
				(clearance 0)
			)
			(min_thickness 0.25)
			(keepout
				(tracks allowed)
				(vias not_allowed)
				(pads allowed)
				(copperpour not_allowed)
				(footprints allowed)
			)
			(placement
				(enabled no)
				(sheetname "")
			)
			(fill
				(thermal_gap 0.5)
				(thermal_bridge_width 0.5)
				(island_removal_mode 0)
			)
			(polygon
				(pts
					(xy 146.3802 -19.7612) (xy 146.3802 -19.6088) (xy 146.9898 -19.6088) (xy 146.9898 -19.7612)
				)
			)
		)
	)
)
